# T6G (Grand Teton) — schematic netlist excerpt (pin names and nets, part order shuffled) for the footprints in the layout excerpt that follows; sources: Cadence DE-HDL packaged netlist, KiCad conversion of 04192023_DAF0TMB3IC0_F0TG_MB_C_brd_V02_OCP.brd

R3094  Q_RES  130 1% CHIP  pkg 0402LF  page 256 : A = LED_PWRGD_PVDDCR_SOC_P1_R ; B = P3V3_AUX
R6757  Q_RES  0 5% CHIP  pkg 0201LF  page 184 : A = SMB_RT_CPU0_P1_SCL ; B = SMB_RT_CPU0_P1_R_SCL
PC152_1  Q_CAP  22UF 16V 20% X6S  pkg C0805  page 205 : A = SW_P12V_AUX_PVDDIO_P0_FLT ; B = GND

(kicad_pcb
	(version 20260206)
	(generator "pcbnew")
	(generator_version "10.0")
	(general
		(thickness 1.6)
		(legacy_teardrops no)
	)
	(paper "A4")
	(title_block
		(title "04192023_DAF0TMB3IC0_F0TG_MB_C_brd_V02_OCP.brd")
		(comment 1 "Grand Teton / footprints 5090-5092 of 8354")
	)
	(layers
		(0 "F.Cu" signal "TOP")
		(4 "In1.Cu" signal "GND")
		(6 "In2.Cu" signal "IN1")
		(8 "In3.Cu" signal "GND1")
		(10 "In4.Cu" signal "IN2")
		(12 "In5.Cu" signal "GND2")
		(14 "In6.Cu" signal "IN3")
		(16 "In7.Cu" signal "GND3")
		(18 "In8.Cu" signal "VCC")
		(20 "In9.Cu" signal "VCC1")
		(22 "In10.Cu" signal "GND4")
		(24 "In11.Cu" signal "IN4")
		(26 "In12.Cu" signal "GND5")
		(28 "In13.Cu" signal "IN5")
		(30 "In14.Cu" signal "GND6")
		(32 "In15.Cu" signal "IN6")
		(34 "In16.Cu" signal "GND7")
		(2 "B.Cu" signal "BOTTOM")
		(9 "F.Adhes" user "F.Adhesive")
		(11 "B.Adhes" user "B.Adhesive")
		(13 "F.Paste" user "Package Geometry/Pastemask Top")
		(15 "B.Paste" user "Package Geometry/Pastemask Bottom")
		(5 "F.SilkS" user "Ref Des/Silkscreen Top")
		(7 "B.SilkS" user "Ref Des/Silkscreen Bottom")
		(1 "F.Mask" user "Board Geometry/Soldermask Top")
		(3 "B.Mask" user "Board Geometry/Soldermask Bottom")
		(17 "Dwgs.User" user "User.Drawings")
		(19 "Cmts.User" user "User.Comments")
		(21 "Eco1.User" user "User.Eco1")
		(23 "Eco2.User" user "User.Eco2")
		(25 "Edge.Cuts" user "Board Geometry/Outline")
		(27 "Margin" user)
		(31 "F.CrtYd" user "Package Geometry/Place Bound Top")
		(29 "B.CrtYd" user "Package Geometry/Place Bound Bottom")
		(35 "F.Fab" user "Ref Des/Assembly Top")
		(33 "B.Fab" user "Ref Des/Assembly Bottom")
	)
	(footprint ""
		(layer "B.Cu")
		(at 230.6828 -338.582 180)
		(property "Reference" "R6757"
			(at 0 0 0)
			(layer "B.SilkS")
			(hide yes)
			(effects
				(font
					(size 1.27 1.27)
				)
				(justify mirror)
			)
		)
		(property "Value" ""
			(at 0 0 0)
			(layer "B.Fab")
			(effects
				(font
					(size 1.27 1.27)
				)
				(justify mirror)
			)
		)
		(duplicate_pad_numbers_are_jumpers no)
		(fp_line
			(start 0.32512 0.175006)
			(end 0.32512 -0.175006)
			(stroke
				(width 0.1)
				(type default)
			)
			(layer "B.Fab")
		)
		(fp_line
			(start 0.32512 -0.175006)
			(end -0.32512 -0.175006)
			(stroke
				(width 0.1)
				(type default)
			)
			(layer "B.Fab")
		)
		(fp_line
			(start -0.32512 0.175006)
			(end 0.32512 0.175006)
			(stroke
				(width 0.1)
				(type default)
			)
			(layer "B.Fab")
		)
		(fp_line
			(start -0.32512 -0.175006)
			(end -0.32512 0.175006)
			(stroke
				(width 0.1)
				(type default)
			)
			(layer "B.Fab")
		)
		(pad "1" smd rect
			(at 0.2667 0)
			(size 0.3048 0.381)
			(layers "B.Cu" "B.Mask" "B.Paste")
			(net "SMB_RT_CPU0_P1_SCL")
		)
		(pad "2" smd rect
			(at -0.2667 0 180)
			(size 0.3048 0.381)
			(layers "B.Cu" "B.Mask" "B.Paste")
			(net "SMB_RT_CPU0_P1_R_SCL")
		)
	)
	(footprint ""
		(layer "B.Cu")
		(at 301.48657 -346.784168 90)
		(property "Reference" "PC152_1"
			(at 0 0 90)
			(layer "B.SilkS")
			(hide yes)
			(effects
				(font
					(size 1.27 1.27)
				)
				(justify mirror)
			)
		)
		(property "Value" ""
			(at 0 0 90)
			(layer "B.Fab")
			(effects
				(font
					(size 1.27 1.27)
				)
				(justify mirror)
			)
		)
		(duplicate_pad_numbers_are_jumpers no)
		(fp_line
			(start 1.524 -0.762)
			(end -1.524 -0.762)
			(stroke
				(width 0.1524)
				(type default)
			)
			(layer "B.SilkS")
		)
		(fp_line
			(start -1.524 -0.762)
			(end -1.524 0.762)
			(stroke
				(width 0.1524)
				(type default)
			)
			(layer "B.SilkS")
		)
		(fp_line
			(start 1.524 0.762)
			(end 1.524 -0.762)
			(stroke
				(width 0.1524)
				(type default)
			)
			(layer "B.SilkS")
		)
		(fp_line
			(start -1.524 0.762)
			(end 1.524 0.762)
			(stroke
				(width 0.1524)
				(type default)
			)
			(layer "B.SilkS")
		)
		(fp_line
			(start 1.1049 -0.724916)
			(end 1.1049 0.724916)
			(stroke
				(width 0.1)
				(type default)
			)
			(layer "B.Fab")
		)
		(fp_line
			(start -1.1049 -0.724916)
			(end 1.1049 -0.724916)
			(stroke
				(width 0.1)
				(type default)
			)
			(layer "B.Fab")
		)
		(fp_line
			(start 1.1049 0.724916)
			(end -1.1049 0.724916)
			(stroke
				(width 0.1)
				(type default)
			)
			(layer "B.Fab")
		)
		(fp_line
			(start -1.1049 0.724916)
			(end -1.1049 -0.724916)
			(stroke
				(width 0.1)
				(type default)
			)
			(layer "B.Fab")
		)
		(pad "1" smd rect
			(at 0.889 0 90)
			(size 1.016 1.27)
			(layers "B.Cu" "B.Mask" "B.Paste")
			(net "SW_P12V_AUX_PVDDIO_P0_FLT")
		)
		(pad "2" smd rect
			(at -0.889 0 90)
			(size 1.016 1.27)
			(layers "B.Cu" "B.Mask" "B.Paste")
			(net "GND")
		)
	)
	(footprint ""
		(layer "B.Cu")
		(at 338.859876 -66.708782 90)
		(property "Reference" "R3094"
			(at 0 0 90)
			(layer "B.SilkS")
			(hide yes)
			(effects
				(font
					(size 1.27 1.27)
				)
				(justify mirror)
			)
		)
		(property "Value" ""
			(at 0 0 90)
			(layer "B.Fab")
			(effects
				(font
					(size 1.27 1.27)
				)
				(justify mirror)
			)
		)
		(duplicate_pad_numbers_are_jumpers no)
		(fp_line
			(start 0.7874 -0.4064)
			(end -0.7874 -0.4064)
			(stroke
				(width 0.1524)
				(type default)
			)
			(layer "B.SilkS")
		)
		(fp_line
			(start -0.7874 -0.4064)
			(end -0.7874 0.4064)
			(stroke
				(width 0.1524)
				(type default)
			)
			(layer "B.SilkS")
		)
		(fp_line
			(start 0.7874 0.4064)
			(end 0.7874 -0.4064)
			(stroke
				(width 0.1524)
				(type default)
			)
			(layer "B.SilkS")
		)
		(fp_line
			(start -0.7874 0.4064)
			(end 0.7874 0.4064)
			(stroke
				(width 0.1524)
				(type default)
			)
			(layer "B.SilkS")
		)
		(fp_line
			(start 0.67945 -0.305054)
			(end 0.12065 -0.305054)
			(stroke
				(width 0.1)
				(type default)
			)
			(layer "B.Fab")
		)
		(fp_line
			(start 0.12065 -0.305054)
			(end 0.12065 -0.2794)
			(stroke
				(width 0.1)
				(type default)
			)
			(layer "B.Fab")
		)
		(fp_line
			(start -0.12065 -0.3048)
			(end -0.67945 -0.3048)
			(stroke
				(width 0.1)
				(type default)
			)
			(layer "B.Fab")
		)
		(fp_line
			(start -0.67945 -0.3048)
			(end -0.67945 0.3048)
			(stroke
				(width 0.1)
				(type default)
			)
			(layer "B.Fab")
		)
		(fp_line
			(start 0.12065 -0.2794)
			(end -0.12065 -0.2794)
			(stroke
				(width 0.1)
				(type default)
			)
			(layer "B.Fab")
		)
		(fp_line
			(start -0.12065 -0.2794)
			(end -0.12065 -0.3048)
			(stroke
				(width 0.1)
				(type default)
			)
			(layer "B.Fab")
		)
		(fp_line
			(start 0.12065 0.2794)
			(end 0.12065 0.3048)
			(stroke
				(width 0.1)
				(type default)
			)
			(layer "B.Fab")
		)
		(fp_line
			(start -0.120396 0.2794)
			(end 0.12065 0.2794)
			(stroke
				(width 0.1)
				(type default)
			)
			(layer "B.Fab")
		)
		(fp_line
			(start 0.67945 0.3048)
			(end 0.67945 -0.305054)
			(stroke
				(width 0.1)
				(type default)
			)
			(layer "B.Fab")
		)
		(fp_line
			(start 0.12065 0.3048)
			(end 0.67945 0.3048)
			(stroke
				(width 0.1)
				(type default)
			)
			(layer "B.Fab")
		)
		(fp_line
			(start -0.120396 0.3048)
			(end -0.120396 0.2794)
			(stroke
				(width 0.1)
				(type default)
			)
			(layer "B.Fab")
		)
		(fp_line
			(start -0.67945 0.3048)
			(end -0.120396 0.3048)
			(stroke
				(width 0.1)
				(type default)
			)
			(layer "B.Fab")
		)
		(pad "1" smd circle
			(at 0.40005 0 270)
			(size 0 0)
			(layers "B.Cu" "B.Mask" "B.Paste")
			(net "LED_PWRGD_PVDDCR_SOC_P1_R")
		)
		(pad "2" smd circle
			(at -0.40005 0 270)
			(size 0 0)
			(layers "B.Cu" "B.Mask" "B.Paste")
			(net "P3V3_AUX")
		)
	)
)
